# S9S_MB_2U (Grand Teton) — schematic netlist excerpt (pin names and nets, part order shuffled) for the footprints in the layout excerpt that follows; sources: Cadence DE-HDL packaged netlist, KiCad conversion of 03242023_DA0F0TMBIJ0_F0T_Motherboard_J_brd_V01_OCP.brd

R933  Q_RES  10K 1% CHIP  pkg 0402LF  page 128 : A = RST_CPU1_DRAM_AB_N ; B = GND

(kicad_pcb
	(version 20260206)
	(generator "pcbnew")
	(generator_version "10.0")
	(general
		(thickness 1.6)
		(legacy_teardrops no)
	)
	(paper "A4")
	(title_block
		(title "03242023_DA0F0TMBIJ0_F0T_Motherboard_J_brd_V01_OCP.brd")
		(comment 1 "Grand Teton / footprints 1606-1606 of 6105")
	)
	(layers
		(0 "F.Cu" signal "TOP")
		(4 "In1.Cu" signal "GND")
		(6 "In2.Cu" signal "IN1")
		(8 "In3.Cu" signal "GND1")
		(10 "In4.Cu" signal "IN2")
		(12 "In5.Cu" signal "GND2")
		(14 "In6.Cu" signal "IN3")
		(16 "In7.Cu" signal "GND3")
		(18 "In8.Cu" signal "VCC")
		(20 "In9.Cu" signal "VCC1")
		(22 "In10.Cu" signal "GND4")
		(24 "In11.Cu" signal "IN4")
		(26 "In12.Cu" signal "GND5")
		(28 "In13.Cu" signal "IN5")
		(30 "In14.Cu" signal "GND6")
		(32 "In15.Cu" signal "IN6")
		(34 "In16.Cu" signal "GND7")
		(2 "B.Cu" signal "BOTTOM")
		(9 "F.Adhes" user "F.Adhesive")
		(11 "B.Adhes" user "B.Adhesive")
		(13 "F.Paste" user "Package Geometry/Pastemask Top")
		(15 "B.Paste" user "Package Geometry/Pastemask Bottom")
		(5 "F.SilkS" user "Ref Des/Silkscreen Top")
		(7 "B.SilkS" user "Ref Des/Silkscreen Bottom")
		(1 "F.Mask" user "Board Geometry/Soldermask Top")
		(3 "B.Mask" user "Board Geometry/Soldermask Bottom")
		(17 "Dwgs.User" user "User.Drawings")
		(19 "Cmts.User" user "User.Comments")
		(21 "Eco1.User" user "User.Eco1")
		(23 "Eco2.User" user "User.Eco2")
		(25 "Edge.Cuts" user "Board Geometry/Outline")
		(27 "Margin" user)
		(31 "F.CrtYd" user "Package Geometry/Place Bound Top")
		(29 "B.CrtYd" user "Package Geometry/Place Bound Bottom")
		(35 "F.Fab" user "Ref Des/Assembly Top")
		(33 "B.Fab" user "Ref Des/Assembly Bottom")
	)
	(footprint ""
		(layer "F.Cu")
		(at 120.438926 -122.096784 90)
		(property "Reference" "R933"
			(at 0 0 90)
			(layer "F.SilkS")
			(hide yes)
			(effects
				(font
					(size 1.27 1.27)
				)
			)
		)
		(property "Value" ""
			(at 0 0 90)
			(layer "F.Fab")
			(effects
				(font
					(size 1.27 1.27)
				)
			)
		)
		(duplicate_pad_numbers_are_jumpers no)
		(fp_line
			(start 0.7874 -0.4064)
			(end 0.7874 0.4064)
			(stroke
				(width 0.1524)
				(type default)
			)
			(layer "F.SilkS")
		)
		(fp_line
			(start -0.7874 -0.4064)
			(end 0.7874 -0.4064)
			(stroke
				(width 0.1524)
				(type default)
			)
			(layer "F.SilkS")
		)
		(fp_line
			(start 0.7874 0.4064)
			(end -0.7874 0.4064)
			(stroke
				(width 0.1524)
				(type default)
			)
			(layer "F.SilkS")
		)
		(fp_line
			(start -0.7874 0.4064)
			(end -0.7874 -0.4064)
			(stroke
				(width 0.1524)
				(type default)
			)
			(layer "F.SilkS")
		)
		(fp_line
			(start -0.12065 -0.305054)
			(end -0.12065 -0.2794)
			(stroke
				(width 0.1)
				(type default)
			)
			(layer "F.Fab")
		)
		(fp_line
			(start -0.67945 -0.305054)
			(end -0.12065 -0.305054)
			(stroke
				(width 0.1)
				(type default)
			)
			(layer "F.Fab")
		)
		(fp_line
			(start 0.67945 -0.3048)
			(end 0.67945 0.3048)
			(stroke
				(width 0.1)
				(type default)
			)
			(layer "F.Fab")
		)
		(fp_line
			(start 0.12065 -0.3048)
			(end 0.67945 -0.3048)
			(stroke
				(width 0.1)
				(type default)
			)
			(layer "F.Fab")
		)
		(fp_line
			(start 0.12065 -0.2794)
			(end 0.12065 -0.3048)
			(stroke
				(width 0.1)
				(type default)
			)
			(layer "F.Fab")
		)
		(fp_line
			(start -0.12065 -0.2794)
			(end 0.12065 -0.2794)
			(stroke
				(width 0.1)
				(type default)
			)
			(layer "F.Fab")
		)
		(fp_line
			(start 0.120396 0.2794)
			(end -0.12065 0.2794)
			(stroke
				(width 0.1)
				(type default)
			)
			(layer "F.Fab")
		)
		(fp_line
			(start -0.12065 0.2794)
			(end -0.12065 0.3048)
			(stroke
				(width 0.1)
				(type default)
			)
			(layer "F.Fab")
		)
		(fp_line
			(start 0.67945 0.3048)
			(end 0.120396 0.3048)
			(stroke
				(width 0.1)
				(type default)
			)
			(layer "F.Fab")
		)
		(fp_line
			(start 0.120396 0.3048)
			(end 0.120396 0.2794)
			(stroke
				(width 0.1)
				(type default)
			)
			(layer "F.Fab")
		)
		(fp_line
			(start -0.12065 0.3048)
			(end -0.67945 0.3048)
			(stroke
				(width 0.1)
				(type default)
			)
			(layer "F.Fab")
		)
		(fp_line
			(start -0.67945 0.3048)
			(end -0.67945 -0.305054)
			(stroke
				(width 0.1)
				(type default)
			)
			(layer "F.Fab")
		)
		(pad "1" smd circle
			(at -0.40005 0 90)
			(size 0 0)
			(layers "F.Cu" "F.Mask" "F.Paste")
			(net "RST_CPU1_DRAM_AB_N")
		)
		(pad "2" smd circle
			(at 0.40005 0 90)
			(size 0 0)
			(layers "F.Cu" "F.Mask" "F.Paste")
			(net "GND")
		)
	)
)
